# BASEBOARD_FAB2 (Tioga Pass) — schematic netlist excerpt (pin names and nets, part order shuffled) for the footprints in the layout excerpt that follows; sources: Cadence DE-HDL packaged netlist, KiCad conversion of Wiwynn_Tioga_Pass_MB.brd

C9M6  CAP_A  0.1UF 16V 10% X7R  pkg 0402V  page 198 : A = P5V_STBY ; B = GND
C2P14  CAP_A  0.1UF 16V 10% X7R  pkg 0402V  page 188 : A = P12V_STBY ; B = GND
R7C26  RES  33.2 1% CHIP  pkg 0402  page 119 : A = CLK_24M_BMC_LPC ; B = CLK_24M_BMC_LPC_R

(kicad_pcb
	(version 20260206)
	(generator "pcbnew")
	(generator_version "10.0")
	(general
		(thickness 1.6)
		(legacy_teardrops no)
	)
	(paper "A4")
	(title_block
		(title "Wiwynn_Tioga_Pass_MB.brd")
		(comment 1 "Tioga Pass / footprints 4064-4066 of 4770")
	)
	(layers
		(0 "F.Cu" signal "TOP")
		(4 "In1.Cu" signal "L2GND")
		(6 "In2.Cu" signal "L3")
		(8 "In3.Cu" signal "L4GND")
		(10 "In4.Cu" signal "L5")
		(12 "In5.Cu" signal "L6GND")
		(14 "In6.Cu" signal "L7VCC")
		(16 "In7.Cu" signal "L8VCC")
		(18 "In8.Cu" signal "L9GND")
		(20 "In9.Cu" signal "L10")
		(22 "In10.Cu" signal "L11GND")
		(24 "In11.Cu" signal "L12")
		(26 "In12.Cu" signal "L13GND")
		(2 "B.Cu" signal "BOTTOM")
		(9 "F.Adhes" user "F.Adhesive")
		(11 "B.Adhes" user "B.Adhesive")
		(13 "F.Paste" user "Package Geometry/Pastemask Top")
		(15 "B.Paste" user "Package Geometry/Pastemask Bottom")
		(5 "F.SilkS" user "Ref Des/Silkscreen Top")
		(7 "B.SilkS" user "Ref Des/Silkscreen Bottom")
		(1 "F.Mask" user "Board Geometry/Soldermask Top")
		(3 "B.Mask" user "Board Geometry/Soldermask Bottom")
		(17 "Dwgs.User" user "User.Drawings")
		(19 "Cmts.User" user "User.Comments")
		(21 "Eco1.User" user "User.Eco1")
		(23 "Eco2.User" user "User.Eco2")
		(25 "Edge.Cuts" user "Board Geometry/Outline")
		(27 "Margin" user)
		(31 "F.CrtYd" user "Package Geometry/Place Bound Top")
		(29 "B.CrtYd" user "Package Geometry/Place Bound Bottom")
		(35 "F.Fab" user "Ref Des/Assembly Top")
		(33 "B.Fab" user "Ref Des/Assembly Bottom")
	)
	(footprint ""
		(layer "B.Cu")
		(at 8.653272 -121.94413 90)
		(property "Reference" "C9M6"
			(at 0 0 90)
			(layer "B.SilkS")
			(hide yes)
			(effects
				(font
					(size 1.27 1.27)
				)
				(justify mirror)
			)
		)
		(property "Value" ""
			(at 0 0 90)
			(layer "B.Fab")
			(effects
				(font
					(size 1.27 1.27)
				)
				(justify mirror)
			)
		)
		(duplicate_pad_numbers_are_jumpers no)
		(fp_rect
			(start 0.3048 0.9906)
			(end -0.3048 -0.1016)
			(stroke
				(width 0)
				(type default)
			)
			(fill no)
			(layer "B.CrtYd")
		)
		(fp_line
			(start 0.3048 -0.1016)
			(end 0.3048 0.9906)
			(stroke
				(width 0.1)
				(type default)
			)
			(layer "B.Fab")
		)
		(fp_line
			(start -0.3048 -0.1016)
			(end 0.3048 -0.1016)
			(stroke
				(width 0.1)
				(type default)
			)
			(layer "B.Fab")
		)
		(fp_line
			(start 0.3048 0.9906)
			(end -0.3048 0.9906)
			(stroke
				(width 0.1)
				(type default)
			)
			(layer "B.Fab")
		)
		(fp_line
			(start -0.3048 0.9906)
			(end -0.3048 -0.1016)
			(stroke
				(width 0.1)
				(type default)
			)
			(layer "B.Fab")
		)
		(pad "1" smd rect
			(at 0 0 270)
			(size 0.508 0.508)
			(layers "B.Cu" "B.Mask" "B.Paste")
			(net "P5V_STBY")
		)
		(pad "2" smd rect
			(at 0 0.889 270)
			(size 0.508 0.508)
			(layers "B.Cu" "B.Mask" "B.Paste")
			(net "GND")
		)
		(zone
			(layer "B.Cu")
			(hatch none 0.5)
			(connect_pads
				(clearance 0)
			)
			(min_thickness 0.25)
			(keepout
				(tracks allowed)
				(vias not_allowed)
				(pads allowed)
				(copperpour not_allowed)
				(footprints allowed)
			)
			(placement
				(enabled no)
				(sheetname "")
			)
			(fill
				(thermal_gap 0.5)
				(thermal_bridge_width 0.5)
				(island_removal_mode 0)
			)
			(polygon
				(pts
					(xy 9.288272 -122.19813) (xy 8.907272 -122.19813) (xy 8.907272 -121.69013) (xy 9.288272 -121.69013)
				)
			)
		)
		(zone
			(layer "B.Cu")
			(hatch none 0.5)
			(connect_pads
				(clearance 0)
			)
			(min_thickness 0.25)
			(keepout
				(tracks not_allowed)
				(vias allowed)
				(pads allowed)
				(copperpour not_allowed)
				(footprints allowed)
			)
			(placement
				(enabled no)
				(sheetname "")
			)
			(fill
				(thermal_gap 0.5)
				(thermal_bridge_width 0.5)
				(island_removal_mode 0)
			)
			(polygon
				(pts
					(xy 9.288272 -122.19813) (xy 8.907272 -122.19813) (xy 8.907272 -121.69013) (xy 9.288272 -121.69013)
				)
			)
		)
	)
	(footprint ""
		(layer "B.Cu")
		(at 444.6778 -64.7446 180)
		(property "Reference" "C2P14"
			(at 0 0 0)
			(layer "B.SilkS")
			(hide yes)
			(effects
				(font
					(size 1.27 1.27)
				)
				(justify mirror)
			)
		)
		(property "Value" ""
			(at 0 0 0)
			(layer "B.Fab")
			(effects
				(font
					(size 1.27 1.27)
				)
				(justify mirror)
			)
		)
		(duplicate_pad_numbers_are_jumpers no)
		(fp_poly
			(pts
				(xy -0.3048 -0.1016) (xy -0.3048 0.9906) (xy 0.3048 0.9906) (xy 0.3048 -0.1016)
			)
			(stroke
				(width 0)
				(type default)
			)
			(fill no)
			(layer "B.CrtYd")
		)
		(fp_line
			(start 0.3048 0.9906)
			(end -0.3048 0.9906)
			(stroke
				(width 0.1)
				(type default)
			)
			(layer "B.Fab")
		)
		(fp_line
			(start 0.3048 -0.1016)
			(end 0.3048 0.9906)
			(stroke
				(width 0.1)
				(type default)
			)
			(layer "B.Fab")
		)
		(fp_line
			(start -0.3048 0.9906)
			(end -0.3048 -0.1016)
			(stroke
				(width 0.1)
				(type default)
			)
			(layer "B.Fab")
		)
		(fp_line
			(start -0.3048 -0.1016)
			(end 0.3048 -0.1016)
			(stroke
				(width 0.1)
				(type default)
			)
			(layer "B.Fab")
		)
		(pad "1" smd rect
			(at 0 0)
			(size 0.508 0.508)
			(layers "B.Cu" "B.Mask" "B.Paste")
			(net "P12V_STBY")
		)
		(pad "2" smd rect
			(at 0 0.889)
			(size 0.508 0.508)
			(layers "B.Cu" "B.Mask" "B.Paste")
			(net "GND")
		)
		(zone
			(layer "B.Cu")
			(hatch none 0.5)
			(connect_pads
				(clearance 0)
			)
			(min_thickness 0.25)
			(keepout
				(tracks not_allowed)
				(vias allowed)
				(pads allowed)
				(copperpour not_allowed)
				(footprints allowed)
			)
			(placement
				(enabled no)
				(sheetname "")
			)
			(fill
				(thermal_gap 0.5)
				(thermal_bridge_width 0.5)
				(island_removal_mode 0)
			)
			(polygon
				(pts
					(xy 444.4238 -65.3796) (xy 444.9318 -65.3796) (xy 444.9318 -64.9986) (xy 444.4238 -64.9986)
				)
			)
		)
		(zone
			(layer "B.Cu")
			(hatch none 0.5)
			(connect_pads
				(clearance 0)
			)
			(min_thickness 0.25)
			(keepout
				(tracks allowed)
				(vias not_allowed)
				(pads allowed)
				(copperpour not_allowed)
				(footprints allowed)
			)
			(placement
				(enabled no)
				(sheetname "")
			)
			(fill
				(thermal_gap 0.5)
				(thermal_bridge_width 0.5)
				(island_removal_mode 0)
			)
			(polygon
				(pts
					(xy 444.4238 -64.9986) (xy 444.9318 -64.9986) (xy 444.9318 -65.3796) (xy 444.4238 -65.3796)
				)
			)
		)
	)
	(footprint ""
		(layer "B.Cu")
		(at 379.481842 -91.021662 180)
		(property "Reference" "R7C26"
			(at 0.8382 -0.67818 180)
			(unlocked yes)
			(layer "B.SilkS")
			(effects
				(font
					(size 0.4064 0.254)
					(thickness 0.1524)
				)
				(justify left mirror)
			)
		)
		(property "Value" ""
			(at 0 0 0)
			(layer "B.Fab")
			(effects
				(font
					(size 1.27 1.27)
				)
				(justify mirror)
			)
		)
		(duplicate_pad_numbers_are_jumpers no)
		(fp_poly
			(pts
				(xy 0.2794 -0.1016) (xy -0.2794 -0.1016) (xy -0.2794 0.9906) (xy 0.2794 0.9906)
			)
			(stroke
				(width 0)
				(type default)
			)
			(fill no)
			(layer "B.CrtYd")
		)
		(fp_line
			(start 0.2794 0.9906)
			(end -0.2794 0.9906)
			(stroke
				(width 0.1)
				(type default)
			)
			(layer "B.Fab")
		)
		(fp_line
			(start 0.2794 -0.1016)
			(end 0.2794 0.9906)
			(stroke
				(width 0.1)
				(type default)
			)
			(layer "B.Fab")
		)
		(fp_line
			(start -0.2794 0.9906)
			(end -0.2794 -0.1016)
			(stroke
				(width 0.1)
				(type default)
			)
			(layer "B.Fab")
		)
		(fp_line
			(start -0.2794 -0.1016)
			(end 0.2794 -0.1016)
			(stroke
				(width 0.1)
				(type default)
			)
			(layer "B.Fab")
		)
		(pad "1" smd rect
			(at 0 0)
			(size 0.508 0.508)
			(layers "B.Cu" "B.Mask" "B.Paste")
			(net "CLK_24M_BMC_LPC")
		)
		(pad "2" smd rect
			(at 0 0.889)
			(size 0.508 0.508)
			(layers "B.Cu" "B.Mask" "B.Paste")
			(net "CLK_24M_BMC_LPC_R")
		)
		(zone
			(layer "B.Cu")
			(hatch none 0.5)
			(connect_pads
				(clearance 0)
			)
			(min_thickness 0.25)
			(keepout
				(tracks not_allowed)
				(vias allowed)
				(pads allowed)
				(copperpour not_allowed)
				(footprints allowed)
			)
			(placement
				(enabled no)
				(sheetname "")
			)
			(fill
				(thermal_gap 0.5)
				(thermal_bridge_width 0.5)
				(island_removal_mode 0)
			)
			(polygon
				(pts
					(xy 379.227842 -91.656662) (xy 379.735842 -91.656662) (xy 379.735842 -91.275662) (xy 379.227842 -91.275662)
				)
			)
		)
		(zone
			(layer "B.Cu")
			(hatch none 0.5)
			(connect_pads
				(clearance 0)
			)
			(min_thickness 0.25)
			(keepout
				(tracks allowed)
				(vias not_allowed)
				(pads allowed)
				(copperpour not_allowed)
				(footprints allowed)
			)
			(placement
				(enabled no)
				(sheetname "")
			)
			(fill
				(thermal_gap 0.5)
				(thermal_bridge_width 0.5)
				(island_removal_mode 0)
			)
			(polygon
				(pts
					(xy 379.227842 -91.275662) (xy 379.735842 -91.275662) (xy 379.735842 -91.656662) (xy 379.227842 -91.656662)
				)
			)
		)
	)
)
